FILE_TYPE = MULTI_PHYS_TABLE;
PART 'NB3W1200L'
{==================================================================================================================================================================}
:PACK_TYPE | MATERIAL | PART_NUMBER     = EnvComp | PART_NUMBER  | JEDEC_TYPE       |             DESCRIPTION            | CLASS | COMPONENT_TYPE | HEIGHT     | LPID   | SPEED_URL | Status |RPL| AML | Bus_Unit | Days ;
{==================================================================================================================================================================}
'LCC'      | 'IC'     | 'H13585-001'(!) = 'YES;YES;YES;UNK;ok;VLD' | 'H13585-001' | 'PQFP64_36_5MC'  | 'IC,CLK_DRVR,64MLF,BUFDR,PLL'      | 'IC'  | 'LCC'          | '0.039 IN' | '2659' | 'http://speed.intel.com:8081/speed/module/pdm/item/pdm_item_detail_direct.asp?item_cde=H13585-001&item_rev=01&url_param=unused' | 'Design' | 'NO' | '2' | 'SMO_IC' | '???' 
'LCC'      | 'EMPTY'  | 'H13585-001'(!) = 'YES;YES;YES;UNK;ok;VLD' | 'H13585-001' | 'PQFP64_36_5MC'  | 'IC,CLK_DRVR,64MLF,BUFDR,PLL'      | 'IO'  | 'LCC'          | '0.039 IN' | '2659' | 'http://speed.intel.com:8081/speed/module/pdm/item/pdm_item_detail_direct.asp?item_cde=H13585-001&item_rev=01&url_param=unused' | 'Design' | 'NO' | '2' | 'SMO_IC' | '???' 
END_PART
END.
